# BASEBOARD_FAB2 (Tioga Pass) — schematic netlist excerpt (pin names and nets, part order shuffled) for the footprints in the layout excerpt that follows; sources: Cadence DE-HDL packaged netlist, KiCad conversion of Wiwynn_Tioga_Pass_MB.brd

C25W66  CAP  1.0UF 16V 10% X6S  pkg 0402  page 149 : A = VCC_VA_3V3 ; B = GND
R8D43  RES  0.0 5% CHIP  pkg 0402  page 104 : A = FM_156M_CPU0_BRD_OSC_EN ; B = FM_CPU0_STL_BRD_OSC_EN
WR8D30  RES  10.0K 1% CHIP  pkg 0402  page 89 : A = FM_ADR_COMPLETE_CPU1_N ; B = IRQ_DIMM_SAVE_CPU1_R_N

(kicad_pcb
	(version 20260206)
	(generator "pcbnew")
	(generator_version "10.0")
	(general
		(thickness 1.6)
		(legacy_teardrops no)
	)
	(paper "A4")
	(title_block
		(title "Wiwynn_Tioga_Pass_MB.brd")
		(comment 1 "Tioga Pass / footprints 4538-4540 of 4770")
	)
	(layers
		(0 "F.Cu" signal "TOP")
		(4 "In1.Cu" signal "L2GND")
		(6 "In2.Cu" signal "L3")
		(8 "In3.Cu" signal "L4GND")
		(10 "In4.Cu" signal "L5")
		(12 "In5.Cu" signal "L6GND")
		(14 "In6.Cu" signal "L7VCC")
		(16 "In7.Cu" signal "L8VCC")
		(18 "In8.Cu" signal "L9GND")
		(20 "In9.Cu" signal "L10")
		(22 "In10.Cu" signal "L11GND")
		(24 "In11.Cu" signal "L12")
		(26 "In12.Cu" signal "L13GND")
		(2 "B.Cu" signal "BOTTOM")
		(9 "F.Adhes" user "F.Adhesive")
		(11 "B.Adhes" user "B.Adhesive")
		(13 "F.Paste" user "Package Geometry/Pastemask Top")
		(15 "B.Paste" user "Package Geometry/Pastemask Bottom")
		(5 "F.SilkS" user "Ref Des/Silkscreen Top")
		(7 "B.SilkS" user "Ref Des/Silkscreen Bottom")
		(1 "F.Mask" user "Board Geometry/Soldermask Top")
		(3 "B.Mask" user "Board Geometry/Soldermask Bottom")
		(17 "Dwgs.User" user "User.Drawings")
		(19 "Cmts.User" user "User.Comments")
		(21 "Eco1.User" user "User.Eco1")
		(23 "Eco2.User" user "User.Eco2")
		(25 "Edge.Cuts" user "Board Geometry/Outline")
		(27 "Margin" user)
		(31 "F.CrtYd" user "Package Geometry/Place Bound Top")
		(29 "B.CrtYd" user "Package Geometry/Place Bound Bottom")
		(35 "F.Fab" user "Ref Des/Assembly Top")
		(33 "B.Fab" user "Ref Des/Assembly Bottom")
	)
	(footprint ""
		(layer "B.Cu")
		(at 352.8949 -73.5838 -90)
		(property "Reference" "R8D43"
			(at 0 0 90)
			(layer "B.SilkS")
			(hide yes)
			(effects
				(font
					(size 1.27 1.27)
				)
				(justify mirror)
			)
		)
		(property "Value" ""
			(at 0 0 90)
			(layer "B.Fab")
			(effects
				(font
					(size 1.27 1.27)
				)
				(justify mirror)
			)
		)
		(duplicate_pad_numbers_are_jumpers no)
		(fp_poly
			(pts
				(xy 0.2794 -0.1016) (xy -0.2794 -0.1016) (xy -0.2794 0.9906) (xy 0.2794 0.9906)
			)
			(stroke
				(width 0)
				(type default)
			)
			(fill no)
			(layer "B.CrtYd")
		)
		(fp_line
			(start -0.2794 0.9906)
			(end -0.2794 -0.1016)
			(stroke
				(width 0.1)
				(type default)
			)
			(layer "B.Fab")
		)
		(fp_line
			(start 0.2794 0.9906)
			(end -0.2794 0.9906)
			(stroke
				(width 0.1)
				(type default)
			)
			(layer "B.Fab")
		)
		(fp_line
			(start -0.2794 -0.1016)
			(end 0.2794 -0.1016)
			(stroke
				(width 0.1)
				(type default)
			)
			(layer "B.Fab")
		)
		(fp_line
			(start 0.2794 -0.1016)
			(end 0.2794 0.9906)
			(stroke
				(width 0.1)
				(type default)
			)
			(layer "B.Fab")
		)
		(pad "1" smd rect
			(at 0 0 90)
			(size 0.508 0.508)
			(layers "B.Cu" "B.Mask" "B.Paste")
			(net "FM_156M_CPU0_BRD_OSC_EN")
		)
		(pad "2" smd rect
			(at 0 0.889 90)
			(size 0.508 0.508)
			(layers "B.Cu" "B.Mask" "B.Paste")
			(net "FM_CPU0_STL_BRD_OSC_EN")
		)
		(zone
			(layer "B.Cu")
			(hatch none 0.5)
			(connect_pads
				(clearance 0)
			)
			(min_thickness 0.25)
			(keepout
				(tracks not_allowed)
				(vias allowed)
				(pads allowed)
				(copperpour not_allowed)
				(footprints allowed)
			)
			(placement
				(enabled no)
				(sheetname "")
			)
			(fill
				(thermal_gap 0.5)
				(thermal_bridge_width 0.5)
				(island_removal_mode 0)
			)
			(polygon
				(pts
					(xy 352.2599 -73.3298) (xy 352.2599 -73.8378) (xy 352.6409 -73.8378) (xy 352.6409 -73.3298)
				)
			)
		)
		(zone
			(layer "B.Cu")
			(hatch none 0.5)
			(connect_pads
				(clearance 0)
			)
			(min_thickness 0.25)
			(keepout
				(tracks allowed)
				(vias not_allowed)
				(pads allowed)
				(copperpour not_allowed)
				(footprints allowed)
			)
			(placement
				(enabled no)
				(sheetname "")
			)
			(fill
				(thermal_gap 0.5)
				(thermal_bridge_width 0.5)
				(island_removal_mode 0)
			)
			(polygon
				(pts
					(xy 352.6409 -73.3298) (xy 352.6409 -73.8378) (xy 352.2599 -73.8378) (xy 352.2599 -73.3298)
				)
			)
		)
	)
	(footprint ""
		(layer "B.Cu")
		(at 411.1625 -27.813 90)
		(property "Reference" "C25W66"
			(at 0.8382 -0.67818 90)
			(unlocked yes)
			(layer "B.SilkS")
			(effects
				(font
					(size 0.4064 0.254)
					(thickness 0.1524)
				)
				(justify left mirror)
			)
		)
		(property "Value" ""
			(at 0 0 90)
			(layer "B.Fab")
			(effects
				(font
					(size 1.27 1.27)
				)
				(justify mirror)
			)
		)
		(duplicate_pad_numbers_are_jumpers no)
		(fp_poly
			(pts
				(xy -0.3048 -0.1016) (xy -0.3048 0.9906) (xy 0.3048 0.9906) (xy 0.3048 -0.1016)
			)
			(stroke
				(width 0)
				(type default)
			)
			(fill no)
			(layer "B.CrtYd")
		)
		(fp_line
			(start 0.3048 -0.1016)
			(end 0.3048 0.9906)
			(stroke
				(width 0.1)
				(type default)
			)
			(layer "B.Fab")
		)
		(fp_line
			(start -0.3048 -0.1016)
			(end 0.3048 -0.1016)
			(stroke
				(width 0.1)
				(type default)
			)
			(layer "B.Fab")
		)
		(fp_line
			(start 0.3048 0.9906)
			(end -0.3048 0.9906)
			(stroke
				(width 0.1)
				(type default)
			)
			(layer "B.Fab")
		)
		(fp_line
			(start -0.3048 0.9906)
			(end -0.3048 -0.1016)
			(stroke
				(width 0.1)
				(type default)
			)
			(layer "B.Fab")
		)
		(pad "1" smd rect
			(at 0 0 270)
			(size 0.508 0.508)
			(layers "B.Cu" "B.Mask" "B.Paste")
			(net "VCC_VA_3V3")
		)
		(pad "2" smd rect
			(at 0 0.889 270)
			(size 0.508 0.508)
			(layers "B.Cu" "B.Mask" "B.Paste")
			(net "GND")
		)
		(zone
			(layer "B.Cu")
			(hatch none 0.5)
			(connect_pads
				(clearance 0)
			)
			(min_thickness 0.25)
			(keepout
				(tracks allowed)
				(vias not_allowed)
				(pads allowed)
				(copperpour not_allowed)
				(footprints allowed)
			)
			(placement
				(enabled no)
				(sheetname "")
			)
			(fill
				(thermal_gap 0.5)
				(thermal_bridge_width 0.5)
				(island_removal_mode 0)
			)
			(polygon
				(pts
					(xy 411.4165 -28.067) (xy 411.4165 -27.559) (xy 411.7975 -27.559) (xy 411.7975 -28.067)
				)
			)
		)
		(zone
			(layer "B.Cu")
			(hatch none 0.5)
			(connect_pads
				(clearance 0)
			)
			(min_thickness 0.25)
			(keepout
				(tracks not_allowed)
				(vias allowed)
				(pads allowed)
				(copperpour not_allowed)
				(footprints allowed)
			)
			(placement
				(enabled no)
				(sheetname "")
			)
			(fill
				(thermal_gap 0.5)
				(thermal_bridge_width 0.5)
				(island_removal_mode 0)
			)
			(polygon
				(pts
					(xy 411.7975 -28.067) (xy 411.7975 -27.559) (xy 411.4165 -27.559) (xy 411.4165 -28.067)
				)
			)
		)
	)
	(footprint ""
		(layer "B.Cu")
		(at 314.0964 -31.718758)
		(property "Reference" "WR8D30"
			(at 0.8382 -0.67818 0)
			(unlocked yes)
			(layer "B.SilkS")
			(effects
				(font
					(size 0.4064 0.254)
					(thickness 0.1524)
				)
				(justify left mirror)
			)
		)
		(property "Value" ""
			(at 0 0 0)
			(layer "B.Fab")
			(effects
				(font
					(size 1.27 1.27)
				)
				(justify mirror)
			)
		)
		(duplicate_pad_numbers_are_jumpers no)
		(fp_poly
			(pts
				(xy 0.2794 -0.1016) (xy -0.2794 -0.1016) (xy -0.2794 0.9906) (xy 0.2794 0.9906)
			)
			(stroke
				(width 0)
				(type default)
			)
			(fill no)
			(layer "B.CrtYd")
		)
		(fp_line
			(start -0.2794 -0.1016)
			(end 0.2794 -0.1016)
			(stroke
				(width 0.1)
				(type default)
			)
			(layer "B.Fab")
		)
		(fp_line
			(start -0.2794 0.9906)
			(end -0.2794 -0.1016)
			(stroke
				(width 0.1)
				(type default)
			)
			(layer "B.Fab")
		)
		(fp_line
			(start 0.2794 -0.1016)
			(end 0.2794 0.9906)
			(stroke
				(width 0.1)
				(type default)
			)
			(layer "B.Fab")
		)
		(fp_line
			(start 0.2794 0.9906)
			(end -0.2794 0.9906)
			(stroke
				(width 0.1)
				(type default)
			)
			(layer "B.Fab")
		)
		(pad "1" smd rect
			(at 0 0 180)
			(size 0.508 0.508)
			(layers "B.Cu" "B.Mask" "B.Paste")
			(net "FM_ADR_COMPLETE_CPU1_N")
		)
		(pad "2" smd rect
			(at 0 0.889 180)
			(size 0.508 0.508)
			(layers "B.Cu" "B.Mask" "B.Paste")
			(net "IRQ_DIMM_SAVE_CPU1_R_N")
		)
		(zone
			(layer "B.Cu")
			(hatch none 0.5)
			(connect_pads
				(clearance 0)
			)
			(min_thickness 0.25)
			(keepout
				(tracks allowed)
				(vias not_allowed)
				(pads allowed)
				(copperpour not_allowed)
				(footprints allowed)
			)
			(placement
				(enabled no)
				(sheetname "")
			)
			(fill
				(thermal_gap 0.5)
				(thermal_bridge_width 0.5)
				(island_removal_mode 0)
			)
			(polygon
				(pts
					(xy 314.3504 -31.464758) (xy 313.8424 -31.464758) (xy 313.8424 -31.083758) (xy 314.3504 -31.083758)
				)
			)
		)
		(zone
			(layer "B.Cu")
			(hatch none 0.5)
			(connect_pads
				(clearance 0)
			)
			(min_thickness 0.25)
			(keepout
				(tracks not_allowed)
				(vias allowed)
				(pads allowed)
				(copperpour not_allowed)
				(footprints allowed)
			)
			(placement
				(enabled no)
				(sheetname "")
			)
			(fill
				(thermal_gap 0.5)
				(thermal_bridge_width 0.5)
				(island_removal_mode 0)
			)
			(polygon
				(pts
					(xy 314.3504 -31.083758) (xy 313.8424 -31.083758) (xy 313.8424 -31.464758) (xy 314.3504 -31.464758)
				)
			)
		)
	)
)
